(kicad_sch (version 20230121) (generator eeschema)

  (paper "A3")

  (title_block
    (title "D1600E PSU Breakout Board")
    (date "2024-08-07")
    (rev "1.4.3")
    (comment 1 "www.antmicro.com")
    (comment 2 "Antmicro Ltd.")
  )

  (junction (at 213.36 118.11) (diameter 0) (color 0 0 0 0)
  )
  (junction (at 241.3 118.11) (diameter 0) (color 0 0 0 0)
  )
  (junction (at 186.69 135.89) (diameter 0) (color 0 0 0 0)
  )
  (junction (at 185.42 151.13) (diameter 0) (color 0 0 0 0)
  )
  (junction (at 179.07 118.11) (diameter 0) (color 0 0 0 0)
  )
  (junction (at 186.69 118.11) (diameter 0) (color 0 0 0 0)
  )
  (junction (at 203.2 142.24) (diameter 0) (color 0 0 0 0)
  )
  (junction (at 185.42 153.67) (diameter 0) (color 0 0 0 0)
  )
  (junction (at 203.2 135.89) (diameter 0) (color 0 0 0 0)
  )

  (wire (pts (xy 213.36 118.11) (xy 213.36 133.35))
    (stroke (width 0) (type default))
  )
  (wire (pts (xy 214.63 118.11) (xy 213.36 118.11))
    (stroke (width 0) (type default))
  )
  (wire (pts (xy 203.2 127) (xy 203.2 135.89))
    (stroke (width 0) (type default))
  )
  (wire (pts (xy 185.42 143.51) (xy 185.42 140.97))
    (stroke (width 0) (type default))
  )
  (wire (pts (xy 185.42 153.67) (xy 185.42 156.21))
    (stroke (width 0) (type default))
  )
  (wire (pts (xy 185.42 162.56) (xy 185.42 161.29))
    (stroke (width 0) (type default))
  )
  (wire (pts (xy 186.69 118.11) (xy 213.36 118.11))
    (stroke (width 0) (type default))
  )
  (wire (pts (xy 179.07 129.54) (xy 179.07 135.89))
    (stroke (width 0) (type default))
  )
  (wire (pts (xy 218.44 142.24) (xy 218.44 140.97))
    (stroke (width 0) (type default))
  )
  (wire (pts (xy 213.36 133.35) (xy 214.63 133.35))
    (stroke (width 0) (type default))
  )
  (wire (pts (xy 203.2 162.56) (xy 203.2 157.48))
    (stroke (width 0) (type default))
  )
  (wire (pts (xy 179.07 135.89) (xy 186.69 135.89))
    (stroke (width 0) (type default))
  )
  (wire (pts (xy 186.69 118.11) (xy 186.69 124.46))
    (stroke (width 0) (type default))
  )
  (wire (pts (xy 175.26 151.13) (xy 185.42 151.13))
    (stroke (width 0) (type default))
  )
  (wire (pts (xy 185.42 153.67) (xy 195.58 153.67))
    (stroke (width 0) (type default))
  )
  (wire (pts (xy 241.3 118.11) (xy 241.3 133.35))
    (stroke (width 0) (type default))
  )
  (wire (pts (xy 210.82 127) (xy 218.44 127))
    (stroke (width 0) (type default))
  )
  (wire (pts (xy 186.69 129.54) (xy 186.69 135.89))
    (stroke (width 0) (type default))
  )
  (wire (pts (xy 203.2 135.89) (xy 203.2 142.24))
    (stroke (width 0) (type default))
  )
  (wire (pts (xy 218.44 127) (xy 218.44 125.73))
    (stroke (width 0) (type default))
  )
  (wire (pts (xy 203.2 142.24) (xy 205.74 142.24))
    (stroke (width 0) (type default))
  )
  (wire (pts (xy 175.26 140.97) (xy 185.42 140.97))
    (stroke (width 0) (type default))
  )
  (wire (pts (xy 227.33 118.11) (xy 241.3 118.11))
    (stroke (width 0) (type default))
  )
  (wire (pts (xy 203.2 142.24) (xy 203.2 144.78))
    (stroke (width 0) (type default))
  )
  (wire (pts (xy 179.07 124.46) (xy 179.07 118.11))
    (stroke (width 0) (type default))
  )
  (wire (pts (xy 241.3 118.11) (xy 243.84 118.11))
    (stroke (width 0) (type default))
  )
  (wire (pts (xy 241.3 133.35) (xy 227.33 133.35))
    (stroke (width 0) (type default))
  )
  (wire (pts (xy 175.26 118.11) (xy 179.07 118.11))
    (stroke (width 0) (type default))
  )
  (wire (pts (xy 210.82 142.24) (xy 218.44 142.24))
    (stroke (width 0) (type default))
  )
  (wire (pts (xy 205.74 127) (xy 203.2 127))
    (stroke (width 0) (type default))
  )
  (wire (pts (xy 185.42 151.13) (xy 185.42 153.67))
    (stroke (width 0) (type default))
  )
  (wire (pts (xy 185.42 148.59) (xy 185.42 151.13))
    (stroke (width 0) (type default))
  )
  (wire (pts (xy 179.07 118.11) (xy 186.69 118.11))
    (stroke (width 0) (type default))
  )
  (wire (pts (xy 186.69 135.89) (xy 203.2 135.89))
    (stroke (width 0) (type default))
  )

  (text "UP TO 15A" (at 165.1 116.84 0)
    (effects (font (size 1.27 1.27)) (justify left bottom))
  )

  (hierarchical_label "VIN12V" (shape input) (at 175.26 118.11 180) (fields_autoplaced)
    (effects (font (size 1.27 1.27)) (justify right))
  )
  (hierarchical_label "VCC3V3" (shape input) (at 175.26 140.97 180) (fields_autoplaced)
    (effects (font (size 1.27 1.27)) (justify right))
  )
  (hierarchical_label "VOUT" (shape output) (at 243.84 118.11 0) (fields_autoplaced)
    (effects (font (size 1.27 1.27)) (justify left))
  )
  (hierarchical_label "SW_ON" (shape input) (at 175.26 151.13 180) (fields_autoplaced)
    (effects (font (size 1.27 1.27)) (justify right))
  )

  (symbol (lib_id "antmicroTransistorsFETsMOSFETsSingle:2N7002_SOT-23-3") (at 195.58 153.67 0) (unit 1)
    (in_bom yes) (on_board yes) (dnp no)
    (property "Reference" "Q6" (at 205.74 148.59 0)
      (effects (font (size 1.27 1.27) (thickness 0.15)) (justify left))
    )
    (property "Value" "2N7002_SOT-23-3" (at 218.44 161.29 0)
      (effects (font (size 1.27 1.27) (thickness 0.15)) (justify left bottom) hide)
    )
    (property "Footprint" "antmicro-footprints:SOT-23-3" (at 218.44 163.83 0)
      (effects (font (size 1.27 1.27) (thickness 0.15)) (justify left bottom) hide)
    )
    (property "Datasheet" "https://www.onsemi.com/pub/Collateral/NDS7002A-D.PDF" (at 218.44 166.37 0)
      (effects (font (size 1.27 1.27) (thickness 0.15)) (justify left bottom) hide)
    )
    (property "MPN" "2N7002" (at 205.74 151.13 0)
      (effects (font (size 1.27 1.27) (thickness 0.15)) (justify left))
    )
    (property "Manufacturer" "ON Semiconductor" (at 218.44 171.45 0)
      (effects (font (size 1.27 1.27) (thickness 0.15)) (justify left bottom) hide)
    )
    (property "Author" "Antmicro" (at 218.44 173.99 0)
      (effects (font (size 1.27 1.27) (thickness 0.15)) (justify left bottom) hide)
    )
    (property "License" "Apache-2.0" (at 218.44 176.53 0)
      (effects (font (size 1.27 1.27) (thickness 0.15)) (justify left bottom) hide)
    )
    (pin "2")
    (pin "3")
    (pin "1")
    (instances
      (project "d1600e-psu-breakout-board"
        (path ""
          (reference "Q6") (unit 1)
        )
        (path ""
          (reference "Q7") (unit 1)
        )
        (path ""
          (reference "Q8") (unit 1)
        )
        (path ""
          (reference "Q9") (unit 1)
        )
        (path ""
          (reference "Q10") (unit 1)
        )
      )
    )
  )

  (symbol (lib_name "SI7613DN-T1-GE3_1") (lib_id "antmicroTransistorsFETsMOSFETsSingle:SI7613DN-T1-GE3") (at 218.44 125.73 270) (mirror x) (unit 1)
    (in_bom yes) (on_board yes) (dnp no)
    (property "Reference" "QB1" (at 226.06 121.92 90)
      (effects (font (size 1.27 1.27)))
    )
    (property "Value" "SI7613DN-T1-GE3" (at 220.98 110.49 0)
      (effects (font (size 1.27 1.27) (thickness 0.15)) (justify left bottom) hide)
    )
    (property "Footprint" "antmicro-footprints:Vishay_PowerPAK_1212-8_Single" (at 219.71 110.49 0)
      (effects (font (size 1.27 1.27) (thickness 0.15)) (justify left bottom) hide)
    )
    (property "Datasheet" "https://www.vishay.com/docs/64809/si7613dn.pdf" (at 217.17 110.49 0)
      (effects (font (size 1.27 1.27) (thickness 0.15)) (justify left bottom) hide)
    )
    (property "MPN" "SI7613DN-T1-GE3" (at 231.14 124.46 90)
      (effects (font (size 1.27 1.27) (thickness 0.15)))
    )
    (property "Manufacturer" "Vishay" (at 210.82 110.49 0)
      (effects (font (size 1.27 1.27) (thickness 0.15)) (justify left bottom) hide)
    )
    (property "Author" "Antmicro" (at 208.28 110.49 0)
      (effects (font (size 1.27 1.27) (thickness 0.15)) (justify left bottom) hide)
    )
    (property "License" "Apache-2.0" (at 205.74 110.49 0)
      (effects (font (size 1.27 1.27) (thickness 0.15)) (justify left bottom) hide)
    )
    (pin "1")
    (pin "2")
    (pin "3")
    (pin "4")
    (pin "5")
    (instances
      (project "d1600e-psu-breakout-board"
        (path ""
          (reference "QB1") (unit 1)
        )
        (path ""
          (reference "QB2") (unit 1)
        )
        (path ""
          (reference "QB3") (unit 1)
        )
        (path ""
          (reference "QB4") (unit 1)
        )
        (path ""
          (reference "QB5") (unit 1)
        )
      )
    )
  )

  (symbol (lib_name "R_4k7_0402_1") (lib_id "antmicroResistors0402:R_4k7_0402") (at 179.07 124.46 270) (unit 1)
    (in_bom yes) (on_board yes) (dnp no)
    (property "Reference" "R22" (at 180.34 125.73 90)
      (effects (font (size 1.27 1.27)) (justify left))
    )
    (property "Value" "R_4k7_0402" (at 166.37 144.78 0)
      (effects (font (size 1.27 1.27) (thickness 0.15)) (justify left bottom) hide)
    )
    (property "Footprint" "antmicro-footprints:R_0402_1005Metric" (at 163.83 144.78 0)
      (effects (font (size 1.27 1.27) (thickness 0.15)) (justify left bottom) hide)
    )
    (property "Datasheet" "https://www.bourns.com/docs/product-datasheets/cr.pdf" (at 161.29 144.78 0)
      (effects (font (size 1.27 1.27) (thickness 0.15)) (justify left bottom) hide)
    )
    (property "Manufacturer" "Bourns" (at 156.21 144.78 0)
      (effects (font (size 1.27 1.27) (thickness 0.15)) (justify left bottom) hide)
    )
    (property "MPN" "CR0402-FX-4701GLF" (at 158.75 144.78 0)
      (effects (font (size 1.27 1.27) (thickness 0.15)) (justify left bottom) hide)
    )
    (property "Val" "4k7" (at 180.34 128.27 90)
      (effects (font (size 1.27 1.27) (thickness 0.15)) (justify left))
    )
    (property "License" "Apache-2.0" (at 153.67 144.78 0)
      (effects (font (size 1.27 1.27) (thickness 0.15)) (justify left bottom) hide)
    )
    (property "Author" "Antmicro" (at 151.13 144.78 0)
      (effects (font (size 1.27 1.27) (thickness 0.15)) (justify left bottom) hide)
    )
    (property "Tolerance" "1%" (at 168.91 144.78 0)
      (effects (font (size 1.27 1.27)) (justify left bottom) hide)
    )
    (pin "1")
    (pin "2")
    (instances
      (project "d1600e-psu-breakout-board"
        (path ""
          (reference "R22") (unit 1)
        )
        (path ""
          (reference "R23") (unit 1)
        )
        (path ""
          (reference "R29") (unit 1)
        )
        (path ""
          (reference "R28") (unit 1)
        )
        (path ""
          (reference "R25") (unit 1)
        )
      )
    )
  )

  (symbol (lib_id "antmicropower:GND") (at 185.42 162.56 0) (unit 1)
    (in_bom yes) (on_board yes) (dnp no)
    (property "Reference" "#PWR049" (at 185.42 168.91 0)
      (effects (font (size 1.27 1.27)) hide)
    )
    (property "Value" "GND" (at 185.42 166.37 0)
      (effects (font (size 1.27 1.27) (thickness 0.15)))
    )
    (property "Footprint" "" (at 194.31 170.18 0)
      (effects (font (size 1.27 1.27) (thickness 0.15)) (justify left bottom) hide)
    )
    (property "Datasheet" "" (at 194.31 175.26 0)
      (effects (font (size 1.27 1.27) (thickness 0.15)) (justify left bottom) hide)
    )
    (property "Author" "Antmicro" (at 194.31 170.18 0)
      (effects (font (size 1.27 1.27) (thickness 0.15)) (justify left bottom) hide)
    )
    (property "License" "Apache-2.0" (at 194.31 172.72 0)
      (effects (font (size 1.27 1.27) (thickness 0.15)) (justify left bottom) hide)
    )
    (pin "1")
    (instances
      (project "d1600e-psu-breakout-board"
        (path ""
          (reference "#PWR049") (unit 1)
        )
        (path ""
          (reference "#PWR059") (unit 1)
        )
        (path ""
          (reference "#PWR050") (unit 1)
        )
        (path ""
          (reference "#PWR053") (unit 1)
        )
        (path ""
          (reference "#PWR066") (unit 1)
        )
      )
    )
  )

  (symbol (lib_id "antmicropower:GND") (at 203.2 162.56 0) (unit 1)
    (in_bom yes) (on_board yes) (dnp no)
    (property "Reference" "#PWR051" (at 203.2 168.91 0)
      (effects (font (size 1.27 1.27)) hide)
    )
    (property "Value" "GND" (at 203.2 166.37 0)
      (effects (font (size 1.27 1.27) (thickness 0.15)))
    )
    (property "Footprint" "" (at 212.09 170.18 0)
      (effects (font (size 1.27 1.27) (thickness 0.15)) (justify left bottom) hide)
    )
    (property "Datasheet" "" (at 212.09 175.26 0)
      (effects (font (size 1.27 1.27) (thickness 0.15)) (justify left bottom) hide)
    )
    (property "Author" "Antmicro" (at 212.09 170.18 0)
      (effects (font (size 1.27 1.27) (thickness 0.15)) (justify left bottom) hide)
    )
    (property "License" "Apache-2.0" (at 212.09 172.72 0)
      (effects (font (size 1.27 1.27) (thickness 0.15)) (justify left bottom) hide)
    )
    (pin "1")
    (instances
      (project "d1600e-psu-breakout-board"
        (path ""
          (reference "#PWR051") (unit 1)
        )
        (path ""
          (reference "#PWR060") (unit 1)
        )
        (path ""
          (reference "#PWR052") (unit 1)
        )
        (path ""
          (reference "#PWR054") (unit 1)
        )
        (path ""
          (reference "#PWR067") (unit 1)
        )
      )
    )
  )

  (symbol (lib_id "antmicroDiodesZenerSingle:BZT52B15SV-T") (at 186.69 124.46 270) (unit 1)
    (in_bom yes) (on_board yes) (dnp no)
    (property "Reference" "D15" (at 187.96 125.73 90)
      (effects (font (size 1.27 1.27)) (justify left))
    )
    (property "Value" "BZT52B15SV-T" (at 176.53 147.32 0)
      (effects (font (size 1.27 1.27) (thickness 0.15)) (justify left bottom) hide)
    )
    (property "Footprint" "antmicro-footprints:D_SOD-323" (at 173.99 147.32 0)
      (effects (font (size 1.27 1.27) (thickness 0.15)) (justify left bottom) hide)
    )
    (property "Datasheet" "https://www.mouser.pl/datasheet/2/345/bzt52bxxsv_series-2301278.pdf" (at 171.45 147.32 0)
      (effects (font (size 1.27 1.27) (thickness 0.15)) (justify left bottom) hide)
    )
    (property "MPN" "BZT52B15SV-T" (at 187.96 128.27 90)
      (effects (font (size 1.27 1.27) (thickness 0.15)) (justify left))
    )
    (property "Manufacturer" "Rectron" (at 168.91 147.32 0)
      (effects (font (size 1.27 1.27) (thickness 0.15)) (justify left bottom) hide)
    )
    (property "Author" "Antmicro" (at 166.37 147.32 0)
      (effects (font (size 1.27 1.27) (thickness 0.15)) (justify left bottom) hide)
    )
    (property "License" "Apache-2.0" (at 163.83 147.32 0)
      (effects (font (size 1.27 1.27) (thickness 0.15)) (justify left bottom) hide)
    )
    (pin "2")
    (pin "1")
    (instances
      (project "d1600e-psu-breakout-board"
        (path ""
          (reference "D15") (unit 1)
        )
        (path ""
          (reference "D16") (unit 1)
        )
        (path ""
          (reference "D18") (unit 1)
        )
        (path ""
          (reference "D17") (unit 1)
        )
        (path ""
          (reference "D19") (unit 1)
        )
      )
    )
  )

  (symbol (lib_name "R_2R_0402_1") (lib_id "antmicroResistors0402:R_2R_0402") (at 210.82 127 180) (unit 1)
    (in_bom yes) (on_board yes) (dnp no)
    (property "Reference" "R60" (at 208.28 124.46 0)
      (effects (font (size 1.27 1.27)))
    )
    (property "Value" "R_2R_0402" (at 190.5 114.3 0)
      (effects (font (size 1.27 1.27) (thickness 0.15)) (justify left bottom) hide)
    )
    (property "Footprint" "antmicro-footprints:R_0402_1005Metric" (at 190.5 111.76 0)
      (effects (font (size 1.27 1.27) (thickness 0.15)) (justify left bottom) hide)
    )
    (property "Datasheet" "https://www.bourns.com/docs/product-datasheets/cr.pdf" (at 190.5 109.22 0)
      (effects (font (size 1.27 1.27) (thickness 0.15)) (justify left bottom) hide)
    )
    (property "Manufacturer" "Bourns" (at 190.5 104.14 0)
      (effects (font (size 1.27 1.27) (thickness 0.15)) (justify left bottom) hide)
    )
    (property "MPN" "CR0402-FX-2R00GLF" (at 190.5 106.68 0)
      (effects (font (size 1.27 1.27) (thickness 0.15)) (justify left bottom) hide)
    )
    (property "Val" "2R" (at 208.28 129.54 0)
      (effects (font (size 1.27 1.27) (thickness 0.15)))
    )
    (property "License" "Apache-2.0" (at 190.5 101.6 0)
      (effects (font (size 1.27 1.27) (thickness 0.15)) (justify left bottom) hide)
    )
    (property "Author" "Antmicro" (at 190.5 99.06 0)
      (effects (font (size 1.27 1.27) (thickness 0.15)) (justify left bottom) hide)
    )
    (property "Tolerance" "1%" (at 190.5 116.84 0)
      (effects (font (size 1.27 1.27)) (justify left bottom) hide)
    )
    (pin "1")
    (pin "2")
    (instances
      (project "d1600e-psu-breakout-board"
        (path ""
          (reference "R60") (unit 1)
        )
        (path ""
          (reference "R61") (unit 1)
        )
        (path ""
          (reference "R65") (unit 1)
        )
        (path ""
          (reference "R64") (unit 1)
        )
        (path ""
          (reference "R68") (unit 1)
        )
      )
    )
  )

  (symbol (lib_name "R_10k_0402_2") (lib_id "antmicroResistors0402:R_10k_0402") (at 185.42 156.21 270) (unit 1)
    (in_bom no) (on_board yes) (dnp yes)
    (property "Reference" "R46" (at 187.325 156.21 90)
      (effects (font (size 1.27 1.27)) (justify left))
    )
    (property "Value" "R_10k_0402" (at 172.72 176.53 0)
      (effects (font (size 1.27 1.27) (thickness 0.15)) (justify left bottom) hide)
    )
    (property "Footprint" "antmicro-footprints:R_0402_1005Metric" (at 170.18 176.53 0)
      (effects (font (size 1.27 1.27) (thickness 0.15)) (justify left bottom) hide)
    )
    (property "Datasheet" "https://www.bourns.com/docs/product-datasheets/cr.pdf" (at 167.64 176.53 0)
      (effects (font (size 1.27 1.27) (thickness 0.15)) (justify left bottom) hide)
    )
    (property "Manufacturer" "Bourns" (at 162.56 176.53 0)
      (effects (font (size 1.27 1.27) (thickness 0.15)) (justify left bottom) hide)
    )
    (property "MPN" "CR0402-FX-1002GLF" (at 165.1 176.53 0)
      (effects (font (size 1.27 1.27) (thickness 0.15)) (justify left bottom) hide)
    )
    (property "Val" "10k" (at 187.325 158.75 90)
      (effects (font (size 1.27 1.27) (thickness 0.15)) (justify left))
    )
    (property "DNP" "DNP" (at 187.325 161.29 90)
      (effects (font (size 1.27 1.27)) (justify left))
    )
    (property "License" "Apache-2.0" (at 160.02 176.53 0)
      (effects (font (size 1.27 1.27) (thickness 0.15)) (justify left bottom) hide)
    )
    (property "Author" "Antmicro" (at 157.48 176.53 0)
      (effects (font (size 1.27 1.27) (thickness 0.15)) (justify left bottom) hide)
    )
    (property "Tolerance" "1%" (at 175.26 176.53 0)
      (effects (font (size 1.27 1.27)) (justify left bottom) hide)
    )
    (pin "1")
    (pin "2")
    (instances
      (project "d1600e-psu-breakout-board"
        (path ""
          (reference "R46") (unit 1)
        )
        (path ""
          (reference "R47") (unit 1)
        )
        (path ""
          (reference "R50") (unit 1)
        )
        (path ""
          (reference "R49") (unit 1)
        )
        (path ""
          (reference "R48") (unit 1)
        )
      )
    )
  )

  (symbol (lib_name "R_2R_0402_2") (lib_id "antmicroResistors0402:R_2R_0402") (at 205.74 142.24 0) (unit 1)
    (in_bom yes) (on_board yes) (dnp no)
    (property "Reference" "R62" (at 208.28 139.7 0)
      (effects (font (size 1.27 1.27)))
    )
    (property "Value" "R_2R_0402" (at 226.06 154.94 0)
      (effects (font (size 1.27 1.27) (thickness 0.15)) (justify left bottom) hide)
    )
    (property "Footprint" "antmicro-footprints:R_0402_1005Metric" (at 226.06 157.48 0)
      (effects (font (size 1.27 1.27) (thickness 0.15)) (justify left bottom) hide)
    )
    (property "Datasheet" "https://www.bourns.com/docs/product-datasheets/cr.pdf" (at 226.06 160.02 0)
      (effects (font (size 1.27 1.27) (thickness 0.15)) (justify left bottom) hide)
    )
    (property "Manufacturer" "Bourns" (at 226.06 165.1 0)
      (effects (font (size 1.27 1.27) (thickness 0.15)) (justify left bottom) hide)
    )
    (property "MPN" "CR0402-FX-2R00GLF" (at 226.06 162.56 0)
      (effects (font (size 1.27 1.27) (thickness 0.15)) (justify left bottom) hide)
    )
    (property "Val" "2R" (at 208.28 144.78 0)
      (effects (font (size 1.27 1.27) (thickness 0.15)))
    )
    (property "License" "Apache-2.0" (at 226.06 167.64 0)
      (effects (font (size 1.27 1.27) (thickness 0.15)) (justify left bottom) hide)
    )
    (property "Author" "Antmicro" (at 226.06 170.18 0)
      (effects (font (size 1.27 1.27) (thickness 0.15)) (justify left bottom) hide)
    )
    (property "Tolerance" "1%" (at 226.06 152.4 0)
      (effects (font (size 1.27 1.27)) (justify left bottom) hide)
    )
    (pin "1")
    (pin "2")
    (instances
      (project "d1600e-psu-breakout-board"
        (path ""
          (reference "R62") (unit 1)
        )
        (path ""
          (reference "R63") (unit 1)
        )
        (path ""
          (reference "R67") (unit 1)
        )
        (path ""
          (reference "R66") (unit 1)
        )
        (path ""
          (reference "R69") (unit 1)
        )
      )
    )
  )

  (symbol (lib_name "SI7613DN-T1-GE3_2") (lib_id "antmicroTransistorsFETsMOSFETsSingle:SI7613DN-T1-GE3") (at 218.44 140.97 270) (mirror x) (unit 1)
    (in_bom yes) (on_board yes) (dnp no)
    (property "Reference" "QA1" (at 226.06 137.16 90)
      (effects (font (size 1.27 1.27)))
    )
    (property "Value" "SI7613DN-T1-GE3" (at 220.98 125.73 0)
      (effects (font (size 1.27 1.27) (thickness 0.15)) (justify left bottom) hide)
    )
    (property "Footprint" "antmicro-footprints:Vishay_PowerPAK_1212-8_Single" (at 219.71 125.73 0)
      (effects (font (size 1.27 1.27) (thickness 0.15)) (justify left bottom) hide)
    )
    (property "Datasheet" "https://www.vishay.com/docs/64809/si7613dn.pdf" (at 217.17 125.73 0)
      (effects (font (size 1.27 1.27) (thickness 0.15)) (justify left bottom) hide)
    )
    (property "MPN" "SI7613DN-T1-GE3" (at 231.14 139.7 90)
      (effects (font (size 1.27 1.27) (thickness 0.15)))
    )
    (property "Manufacturer" "Vishay" (at 210.82 125.73 0)
      (effects (font (size 1.27 1.27) (thickness 0.15)) (justify left bottom) hide)
    )
    (property "Author" "Antmicro" (at 208.28 125.73 0)
      (effects (font (size 1.27 1.27) (thickness 0.15)) (justify left bottom) hide)
    )
    (property "License" "Apache-2.0" (at 205.74 125.73 0)
      (effects (font (size 1.27 1.27) (thickness 0.15)) (justify left bottom) hide)
    )
    (pin "1")
    (pin "2")
    (pin "3")
    (pin "4")
    (pin "5")
    (instances
      (project "d1600e-psu-breakout-board"
        (path ""
          (reference "QA1") (unit 1)
        )
        (path ""
          (reference "QA2") (unit 1)
        )
        (path ""
          (reference "QA3") (unit 1)
        )
        (path ""
          (reference "QA4") (unit 1)
        )
        (path ""
          (reference "QA5") (unit 1)
        )
      )
    )
  )

  (symbol (lib_name "R_10k_0402_1") (lib_id "antmicroResistors0402:R_10k_0402") (at 185.42 143.51 270) (unit 1)
    (in_bom yes) (on_board yes) (dnp no)
    (property "Reference" "R20" (at 187.325 144.78 90)
      (effects (font (size 1.27 1.27)) (justify left))
    )
    (property "Value" "R_10k_0402" (at 172.72 163.83 0)
      (effects (font (size 1.27 1.27) (thickness 0.15)) (justify left bottom) hide)
    )
    (property "Footprint" "antmicro-footprints:R_0402_1005Metric" (at 170.18 163.83 0)
      (effects (font (size 1.27 1.27) (thickness 0.15)) (justify left bottom) hide)
    )
    (property "Datasheet" "https://www.bourns.com/docs/product-datasheets/cr.pdf" (at 167.64 163.83 0)
      (effects (font (size 1.27 1.27) (thickness 0.15)) (justify left bottom) hide)
    )
    (property "Manufacturer" "Bourns" (at 162.56 163.83 0)
      (effects (font (size 1.27 1.27) (thickness 0.15)) (justify left bottom) hide)
    )
    (property "MPN" "CR0402-FX-1002GLF" (at 165.1 163.83 0)
      (effects (font (size 1.27 1.27) (thickness 0.15)) (justify left bottom) hide)
    )
    (property "Val" "10k" (at 187.325 147.32 90)
      (effects (font (size 1.27 1.27) (thickness 0.15)) (justify left))
    )
    (property "License" "Apache-2.0" (at 160.02 163.83 0)
      (effects (font (size 1.27 1.27) (thickness 0.15)) (justify left bottom) hide)
    )
    (property "Author" "Antmicro" (at 157.48 163.83 0)
      (effects (font (size 1.27 1.27) (thickness 0.15)) (justify left bottom) hide)
    )
    (property "Tolerance" "1%" (at 175.26 163.83 0)
      (effects (font (size 1.27 1.27)) (justify left bottom) hide)
    )
    (pin "1")
    (pin "2")
    (instances
      (project "d1600e-psu-breakout-board"
        (path ""
          (reference "R20") (unit 1)
        )
        (path ""
          (reference "R21") (unit 1)
        )
        (path ""
          (reference "R27") (unit 1)
        )
        (path ""
          (reference "R26") (unit 1)
        )
        (path ""
          (reference "R24") (unit 1)
        )
      )
    )
  )
)
